# BASEBOARD_FAB2 (Tioga Pass) — schematic netlist excerpt (pin names and nets, part order shuffled) for the footprints in the layout excerpt that follows; sources: Cadence DE-HDL packaged netlist, KiCad conversion of Wiwynn_Tioga_Pass_MB.brd

R7G114  RES  0.0 5% CHIP  pkg 0402  page 189 : A = BMC_JTAG_SEL_N ; B = BMC_JTAG_SEL_N_MUX
C4E10  CAP  1.0UF 16V 10% X6S  pkg 0402  page 202 : A = VR_PVCCIN_CPU0_PH1_VCIN ; B = GND
R7A18  RES  0.0 5% CHIP  pkg 0402  page 236 : A = GND ; B = VSENSE_PVNN_PCH_STBY_AVSN

(kicad_pcb
	(version 20260206)
	(generator "pcbnew")
	(generator_version "10.0")
	(general
		(thickness 1.6)
		(legacy_teardrops no)
	)
	(paper "A4")
	(title_block
		(title "Wiwynn_Tioga_Pass_MB.brd")
		(comment 1 "Tioga Pass / footprints 632-634 of 4770")
	)
	(layers
		(0 "F.Cu" signal "TOP")
		(4 "In1.Cu" signal "L2GND")
		(6 "In2.Cu" signal "L3")
		(8 "In3.Cu" signal "L4GND")
		(10 "In4.Cu" signal "L5")
		(12 "In5.Cu" signal "L6GND")
		(14 "In6.Cu" signal "L7VCC")
		(16 "In7.Cu" signal "L8VCC")
		(18 "In8.Cu" signal "L9GND")
		(20 "In9.Cu" signal "L10")
		(22 "In10.Cu" signal "L11GND")
		(24 "In11.Cu" signal "L12")
		(26 "In12.Cu" signal "L13GND")
		(2 "B.Cu" signal "BOTTOM")
		(9 "F.Adhes" user "F.Adhesive")
		(11 "B.Adhes" user "B.Adhesive")
		(13 "F.Paste" user "Package Geometry/Pastemask Top")
		(15 "B.Paste" user "Package Geometry/Pastemask Bottom")
		(5 "F.SilkS" user "Ref Des/Silkscreen Top")
		(7 "B.SilkS" user "Ref Des/Silkscreen Bottom")
		(1 "F.Mask" user "Board Geometry/Soldermask Top")
		(3 "B.Mask" user "Board Geometry/Soldermask Bottom")
		(17 "Dwgs.User" user "User.Drawings")
		(19 "Cmts.User" user "User.Comments")
		(21 "Eco1.User" user "User.Eco1")
		(23 "Eco2.User" user "User.Eco2")
		(25 "Edge.Cuts" user "Board Geometry/Outline")
		(27 "Margin" user)
		(31 "F.CrtYd" user "Package Geometry/Place Bound Top")
		(29 "B.CrtYd" user "Package Geometry/Place Bound Bottom")
		(35 "F.Fab" user "Ref Des/Assembly Top")
		(33 "B.Fab" user "Ref Des/Assembly Bottom")
	)
	(footprint ""
		(layer "F.Cu")
		(at 399.770092 -0.109474 90)
		(property "Reference" "R7G114"
			(at -0.8382 -0.67818 90)
			(unlocked yes)
			(layer "F.SilkS")
			(effects
				(font
					(size 0.4064 0.254)
					(thickness 0.1524)
				)
				(justify left)
			)
		)
		(property "Value" ""
			(at 0 0 90)
			(layer "F.Fab")
			(effects
				(font
					(size 1.27 1.27)
				)
			)
		)
		(duplicate_pad_numbers_are_jumpers no)
		(fp_poly
			(pts
				(xy -0.2794 -0.1016) (xy 0.2794 -0.1016) (xy 0.2794 0.9906) (xy -0.2794 0.9906)
			)
			(stroke
				(width 0)
				(type default)
			)
			(fill no)
			(layer "F.CrtYd")
		)
		(fp_line
			(start 0.2794 -0.1016)
			(end -0.2794 -0.1016)
			(stroke
				(width 0.1)
				(type default)
			)
			(layer "F.Fab")
		)
		(fp_line
			(start -0.2794 -0.1016)
			(end -0.2794 0.9906)
			(stroke
				(width 0.1)
				(type default)
			)
			(layer "F.Fab")
		)
		(fp_line
			(start 0.2794 0.9906)
			(end 0.2794 -0.1016)
			(stroke
				(width 0.1)
				(type default)
			)
			(layer "F.Fab")
		)
		(fp_line
			(start -0.2794 0.9906)
			(end 0.2794 0.9906)
			(stroke
				(width 0.1)
				(type default)
			)
			(layer "F.Fab")
		)
		(pad "1" smd rect
			(at 0 0 90)
			(size 0.508 0.508)
			(layers "F.Cu" "F.Mask" "F.Paste")
			(net "BMC_JTAG_SEL_N")
		)
		(pad "2" smd rect
			(at 0 0.889 90)
			(size 0.508 0.508)
			(layers "F.Cu" "F.Mask" "F.Paste")
			(net "BMC_JTAG_SEL_N_MUX")
		)
		(zone
			(layer "F.Cu")
			(hatch none 0.5)
			(connect_pads
				(clearance 0)
			)
			(min_thickness 0.25)
			(keepout
				(tracks allowed)
				(vias not_allowed)
				(pads allowed)
				(copperpour not_allowed)
				(footprints allowed)
			)
			(placement
				(enabled no)
				(sheetname "")
			)
			(fill
				(thermal_gap 0.5)
				(thermal_bridge_width 0.5)
				(island_removal_mode 0)
			)
			(polygon
				(pts
					(xy 400.024092 0.144526) (xy 400.024092 -0.363474) (xy 400.405092 -0.363474) (xy 400.405092 0.144526)
				)
			)
		)
		(zone
			(layer "F.Cu")
			(hatch none 0.5)
			(connect_pads
				(clearance 0)
			)
			(min_thickness 0.25)
			(keepout
				(tracks not_allowed)
				(vias allowed)
				(pads allowed)
				(copperpour not_allowed)
				(footprints allowed)
			)
			(placement
				(enabled no)
				(sheetname "")
			)
			(fill
				(thermal_gap 0.5)
				(thermal_bridge_width 0.5)
				(island_removal_mode 0)
			)
			(polygon
				(pts
					(xy 400.405092 0.144526) (xy 400.405092 -0.363474) (xy 400.024092 -0.363474) (xy 400.024092 0.144526)
				)
			)
		)
	)
	(footprint ""
		(layer "F.Cu")
		(at 368.0206 -136.4234 180)
		(property "Reference" "R7A18"
			(at 0 0 180)
			(layer "F.SilkS")
			(hide yes)
			(effects
				(font
					(size 1.27 1.27)
				)
			)
		)
		(property "Value" ""
			(at 0 0 180)
			(layer "F.Fab")
			(effects
				(font
					(size 1.27 1.27)
				)
			)
		)
		(duplicate_pad_numbers_are_jumpers no)
		(fp_poly
			(pts
				(xy -0.2794 -0.1016) (xy 0.2794 -0.1016) (xy 0.2794 0.9906) (xy -0.2794 0.9906)
			)
			(stroke
				(width 0)
				(type default)
			)
			(fill no)
			(layer "F.CrtYd")
		)
		(fp_line
			(start 0.2794 0.9906)
			(end 0.2794 -0.1016)
			(stroke
				(width 0.1)
				(type default)
			)
			(layer "F.Fab")
		)
		(fp_line
			(start 0.2794 -0.1016)
			(end -0.2794 -0.1016)
			(stroke
				(width 0.1)
				(type default)
			)
			(layer "F.Fab")
		)
		(fp_line
			(start -0.2794 0.9906)
			(end 0.2794 0.9906)
			(stroke
				(width 0.1)
				(type default)
			)
			(layer "F.Fab")
		)
		(fp_line
			(start -0.2794 -0.1016)
			(end -0.2794 0.9906)
			(stroke
				(width 0.1)
				(type default)
			)
			(layer "F.Fab")
		)
		(pad "1" smd rect
			(at 0 0 180)
			(size 0.508 0.508)
			(layers "F.Cu" "F.Mask" "F.Paste")
			(net "GND")
		)
		(pad "2" smd rect
			(at 0 0.889 180)
			(size 0.508 0.508)
			(layers "F.Cu" "F.Mask" "F.Paste")
			(net "VSENSE_PVNN_PCH_STBY_AVSN")
		)
		(zone
			(layer "F.Cu")
			(hatch none 0.5)
			(connect_pads
				(clearance 0)
			)
			(min_thickness 0.25)
			(keepout
				(tracks not_allowed)
				(vias allowed)
				(pads allowed)
				(copperpour not_allowed)
				(footprints allowed)
			)
			(placement
				(enabled no)
				(sheetname "")
			)
			(fill
				(thermal_gap 0.5)
				(thermal_bridge_width 0.5)
				(island_removal_mode 0)
			)
			(polygon
				(pts
					(xy 368.2746 -137.0584) (xy 367.7666 -137.0584) (xy 367.7666 -136.6774) (xy 368.2746 -136.6774)
				)
			)
		)
		(zone
			(layer "F.Cu")
			(hatch none 0.5)
			(connect_pads
				(clearance 0)
			)
			(min_thickness 0.25)
			(keepout
				(tracks allowed)
				(vias not_allowed)
				(pads allowed)
				(copperpour not_allowed)
				(footprints allowed)
			)
			(placement
				(enabled no)
				(sheetname "")
			)
			(fill
				(thermal_gap 0.5)
				(thermal_bridge_width 0.5)
				(island_removal_mode 0)
			)
			(polygon
				(pts
					(xy 368.2746 -136.6774) (xy 367.7666 -136.6774) (xy 367.7666 -137.0584) (xy 368.2746 -137.0584)
				)
			)
		)
	)
	(footprint ""
		(layer "F.Cu")
		(at 197.162928 -53.221382 -90)
		(property "Reference" "C4E10"
			(at 0 0 270)
			(layer "F.SilkS")
			(hide yes)
			(effects
				(font
					(size 1.27 1.27)
				)
			)
		)
		(property "Value" ""
			(at 0 0 270)
			(layer "F.Fab")
			(effects
				(font
					(size 1.27 1.27)
				)
			)
		)
		(duplicate_pad_numbers_are_jumpers no)
		(fp_poly
			(pts
				(xy 0.3048 -0.1016) (xy 0.3048 0.9906) (xy -0.3048 0.9906) (xy -0.3048 -0.1016)
			)
			(stroke
				(width 0)
				(type default)
			)
			(fill no)
			(layer "F.CrtYd")
		)
		(fp_line
			(start -0.3048 0.9906)
			(end 0.3048 0.9906)
			(stroke
				(width 0.1)
				(type default)
			)
			(layer "F.Fab")
		)
		(fp_line
			(start 0.3048 0.9906)
			(end 0.3048 -0.1016)
			(stroke
				(width 0.1)
				(type default)
			)
			(layer "F.Fab")
		)
		(fp_line
			(start -0.3048 -0.1016)
			(end -0.3048 0.9906)
			(stroke
				(width 0.1)
				(type default)
			)
			(layer "F.Fab")
		)
		(fp_line
			(start 0.3048 -0.1016)
			(end -0.3048 -0.1016)
			(stroke
				(width 0.1)
				(type default)
			)
			(layer "F.Fab")
		)
		(pad "1" smd rect
			(at 0 0 270)
			(size 0.508 0.508)
			(layers "F.Cu" "F.Mask" "F.Paste")
			(net "VR_PVCCIN_CPU0_PH1_VCIN")
		)
		(pad "2" smd rect
			(at 0 0.889 270)
			(size 0.508 0.508)
			(layers "F.Cu" "F.Mask" "F.Paste")
			(net "GND")
		)
		(zone
			(layer "F.Cu")
			(hatch none 0.5)
			(connect_pads
				(clearance 0)
			)
			(min_thickness 0.25)
			(keepout
				(tracks not_allowed)
				(vias allowed)
				(pads allowed)
				(copperpour not_allowed)
				(footprints allowed)
			)
			(placement
				(enabled no)
				(sheetname "")
			)
			(fill
				(thermal_gap 0.5)
				(thermal_bridge_width 0.5)
				(island_removal_mode 0)
			)
			(polygon
				(pts
					(xy 196.527928 -53.475382) (xy 196.527928 -52.967382) (xy 196.908928 -52.967382) (xy 196.908928 -53.475382)
				)
			)
		)
		(zone
			(layer "F.Cu")
			(hatch none 0.5)
			(connect_pads
				(clearance 0)
			)
			(min_thickness 0.25)
			(keepout
				(tracks allowed)
				(vias not_allowed)
				(pads allowed)
				(copperpour not_allowed)
				(footprints allowed)
			)
			(placement
				(enabled no)
				(sheetname "")
			)
			(fill
				(thermal_gap 0.5)
				(thermal_bridge_width 0.5)
				(island_removal_mode 0)
			)
			(polygon
				(pts
					(xy 196.908928 -53.475382) (xy 196.908928 -52.967382) (xy 196.527928 -52.967382) (xy 196.527928 -53.475382)
				)
			)
		)
	)
)
